FILE_TYPE = CONNECTIVITY;
{Allegro Design Entry HDL 17.2-2016 S081 (4005846) 1/11/2022}
"PAGE_NUMBER" = 290;
0"NC";
%"ME_DUMMY_SYMBOL"
"1","(3600,3275)","0","pure_quanta","I10";
;
PART_NUMBER"DUMMY48"
PART_TYPE"MECH"
VALUE"PICKUP_SMDC20"
MATERIAL"EMPTY"
$LOCATION"ME2"
PIN_NAMES_ROTATE"True"
PIN_TEXT_VISIBLE"True"
NEEDS_NO_SIZE"TRUE"
CDS_LMAN_SYM_OUTLINE"-200,125,200,-125"
CDS_LIB"pure_quanta"
$LOCATION"ME2"
CDS_LOCATION"ME2";
%"ME_DUMMY_SYMBOL"
"1","(3600,2700)","0","pure_quanta","I11";
;
PART_NUMBER"DUMMY48"
MATERIAL"EMPTY"
PART_TYPE"MECH"
VALUE"PICKUP_SMDC20"
$LOCATION"ME3"
PIN_NAMES_ROTATE"True"
PIN_TEXT_VISIBLE"True"
NEEDS_NO_SIZE"TRUE"
CDS_LMAN_SYM_OUTLINE"-200,125,200,-125"
CDS_LIB"pure_quanta"
$LOCATION"ME3"
CDS_LOCATION"ME3";
%"ME_DUMMY_SYMBOL"
"1","(4245,1955)","0","pure_quanta","I12";
;
PART_NUMBER"DUMMY48"
PART_TYPE"MECH"
MATERIAL"EMPTY"
VALUE"PICKUP_SMDC20"
$LOCATION"ME15"
PIN_NAMES_ROTATE"True"
PIN_TEXT_VISIBLE"True"
NEEDS_NO_SIZE"TRUE"
CDS_LMAN_SYM_OUTLINE"-200,125,200,-125"
CDS_LIB"pure_quanta"
CDS_LOCATION"ME15";
%"ME_DUMMY_SYMBOL"
"1","(3605,1960)","0","pure_quanta","I13";
;
PART_NUMBER"DUMMY48"
PART_TYPE"MECH"
MATERIAL"EMPTY"
VALUE"PICKUP_SMDC20"
$LOCATION"ME13"
PIN_NAMES_ROTATE"True"
PIN_TEXT_VISIBLE"True"
NEEDS_NO_SIZE"TRUE"
CDS_LMAN_SYM_OUTLINE"-200,125,200,-125"
CDS_LIB"pure_quanta"
CDS_LOCATION"ME13";
%"ME_DUMMY_SYMBOL"
"1","(5615,3270)","0","pure_quanta","I14";
;
PART_NUMBER"DUMMY48"
PART_TYPE"MECH"
MATERIAL"EMPTY"
VALUE"PICKUP_SMDC20"
$LOCATION"ME11"
PIN_NAMES_ROTATE"True"
PIN_TEXT_VISIBLE"True"
NEEDS_NO_SIZE"TRUE"
CDS_LIB"pure_quanta"
CDS_LMAN_SYM_OUTLINE"-200,125,200,-125"
CDS_LOCATION"ME11";
%"ME_DUMMY_SYMBOL"
"1","(5620,2640)","0","pure_quanta","I15";
;
PART_NUMBER"DUMMY48"
MATERIAL"EMPTY"
VALUE"PICKUP_SMDC20"
PART_TYPE"MECH"
$LOCATION"ME12"
NEEDS_NO_SIZE"TRUE"
PIN_TEXT_VISIBLE"True"
PIN_NAMES_ROTATE"True"
CDS_LIB"pure_quanta"
CDS_LMAN_SYM_OUTLINE"-200,125,200,-125"
CDS_LOCATION"ME12";
%"ME_DUMMY_SYMBOL"
"1","(3610,1330)","0","pure_quanta","I16";
;
PART_NUMBER"DUMMY48"
MATERIAL"EMPTY"
PART_TYPE"MECH"
VALUE"PICKUP_SMDC20"
$LOCATION"ME14"
NEEDS_NO_SIZE"TRUE"
PIN_TEXT_VISIBLE"True"
PIN_NAMES_ROTATE"True"
CDS_LMAN_SYM_OUTLINE"-200,125,200,-125"
CDS_LIB"pure_quanta"
CDS_LOCATION"ME14";
%"DUMMY_SYMBOL"
"1","(2275,3125)","0","pure_quanta","I17";
;
PART_NUMBER"DUMMY12"
VALUE"BATTERY_SYMBOL"
L1"AHL03003003"
MATERIAL"MECH"
PART_TYPE"MECH"
$LOCATION"DM13"
PIN_NAMES_ROTATE"True"
CDS_LMAN_SYM_OUTLINE"-200,75,200,-75"
CDS_LIB"pure_quanta"
CDS_LOCATION"DM13"
$SEC"1"
CDS_SEC"1";
"1"
$PN"1"0;
%"ME_DUMMY_SYMBOL"
"1","(4975,3275)","0","pure_quanta","I18";
;
PART_NUMBER"DUMMY48"
MATERIAL"EMPTY"
PART_TYPE"MECH"
VALUE"PICKUP_SMDC20"
$LOCATION"ME9"
PIN_NAMES_ROTATE"True"
PIN_TEXT_VISIBLE"True"
NEEDS_NO_SIZE"TRUE"
CDS_LIB"pure_quanta"
CDS_LMAN_SYM_OUTLINE"-200,125,200,-125"
CDS_LOCATION"ME9";
%"ME_DUMMY_SYMBOL"
"1","(4980,2645)","0","pure_quanta","I19";
;
PART_NUMBER"DUMMY48"
MATERIAL"EMPTY"
PART_TYPE"MECH"
VALUE"PICKUP_SMDC20"
$LOCATION"ME10"
NEEDS_NO_SIZE"TRUE"
PIN_TEXT_VISIBLE"True"
PIN_NAMES_ROTATE"True"
CDS_LMAN_SYM_OUTLINE"-200,125,200,-125"
CDS_LIB"pure_quanta"
CDS_LOCATION"ME10";
%"DUMMY_SYMBOL"
"1","(-132,3078)","0","pure_quanta","I23";
;
PART_NUMBER"DUMMY10"
MATERIAL"MECH"
PART_TYPE"MECH"
VALUE"MECHANIC_SYMBOL"
$LOCATION"DM9"
PIN_NAMES_ROTATE"True"
CDS_LMAN_SYM_OUTLINE"-200,75,200,-75"
CDS_LIB"pure_quanta"
CDS_LOCATION"DM9"
$SEC"1"
CDS_SEC"1";
"1"
$PN"1"0;
%"TP"
"1","(-500,800)","0","pure_quanta","I40";
;
PART_NUMBER"TP12_BOM"
MATERIAL"NA"
LOCATION"U1_BL"
QPN"DGRA^000178"
CDS_LIB"pure_quanta"
PACK_TYPE"TP_BOM ONLY"
$SEC"1"
CDS_SEC"1";
"TP \B"
$PN"1"
$PIN_NUMBER"?"0;
%"TP"
"1","(50,800)","0","pure_quanta","I41";
;
PART_NUMBER"TP12_BOM"
QPN"DGRA^000178"
MATERIAL"NA"
LOCATION"U2_BL"
CDS_LIB"pure_quanta"
PACK_TYPE"TP_BOM ONLY"
$SEC"1"
CDS_SEC"1";
"TP \B"
$PN"1"
$PIN_NUMBER"?"0;
%"TP"
"1","(50,250)","0","pure_quanta","I42";
;
PART_NUMBER"TP12_BOM"
QPN"DGRA^000128"
MATERIAL"NA"
LOCATION"U2_BP"
CDS_LIB"pure_quanta"
PACK_TYPE"TP_BOM ONLY"
$SEC"1"
CDS_SEC"1";
"TP \B"
$PN"1"
$PIN_NUMBER"?"0;
%"TP"
"1","(-500,250)","0","pure_quanta","I43";
;
PART_NUMBER"TP12_BOM"
QPN"DGRA^000128"
MATERIAL"NA"
LOCATION"U1_BP"
CDS_LIB"pure_quanta"
PACK_TYPE"TP_BOM ONLY"
$SEC"1"
CDS_SEC"1";
"TP \B"
$PN"1"
$PIN_NUMBER"?"0;
%"TP"
"1","(1375,250)","0","pure_quanta","I45";
;
PART_NUMBER"TP12_BOM"
MATERIAL"NA"
QPN"DGRA^000180"
LOCATION"U2_DC"
CDS_LIB"pure_quanta"
PACK_TYPE"TP_BOM ONLY"
$SEC"1"
CDS_SEC"1";
"TP \B"
$PN"1"
$PIN_NUMBER"?"0;
%"TP"
"1","(825,250)","0","pure_quanta","I47";
;
PART_NUMBER"TP12_BOM"
MATERIAL"NA"
QPN"DGRA^000180"
LOCATION"U1_DC"
CDS_LIB"pure_quanta"
PACK_TYPE"TP_BOM ONLY"
$SEC"1"
CDS_SEC"1";
"TP \B"
$PN"1"
$PIN_NUMBER"?"0;
%"ME_DUMMY_SYMBOL"
"1","(-2775,4475)","0","pure_quanta","I62";
;
PART_NUMBER"DUMMY1"
VALUE"QUANTA_LOGO_7X26"
PART_TYPE"MECH"
MATERIAL"EMPTY"
$LOCATION"ME17"
PIN_NAMES_ROTATE"True"
PIN_TEXT_VISIBLE"True"
NEEDS_NO_SIZE"TRUE"
CDS_LMAN_SYM_OUTLINE"-200,125,200,-125"
CDS_LIB"pure_quanta"
CDS_LOCATION"ME17";
%"ME_DUMMY_SYMBOL"
"1","(-1475,4475)","0","pure_quanta","I63";
;
PART_NUMBER"DUMMY2"
MATERIAL"EMPTY"
PART_TYPE"MECH"
VALUE"WEEE"
$LOCATION"ME18"
PIN_NAMES_ROTATE"True"
PIN_TEXT_VISIBLE"True"
NEEDS_NO_SIZE"TRUE"
CDS_LMAN_SYM_OUTLINE"-200,125,200,-125"
CDS_LIB"pure_quanta"
CDS_LOCATION"ME18";
%"ME_DUMMY_SYMBOL"
"1","(-50,4500)","0","pure_quanta","I64";
;
PART_NUMBER"DUMMY3"
MATERIAL"EMPTY"
PART_TYPE"MECH"
VALUE"PB-E1_SMALL"
$LOCATION"ME20"
PIN_NAMES_ROTATE"True"
PIN_TEXT_VISIBLE"True"
NEEDS_NO_SIZE"TRUE"
CDS_LMAN_SYM_OUTLINE"-200,125,200,-125"
CDS_LIB"pure_quanta"
CDS_LOCATION"ME20";
%"ME_DUMMY_SYMBOL"
"1","(4900,4350)","0","pure_quanta","I65";
;
PART_NUMBER"DUMMY7"
PART_TYPE"MECH"
VALUE"PCB_VENDOR_LOGO_15X8"
MATERIAL"EMPTY"
$LOCATION"ME21"
CDS_LMAN_SYM_OUTLINE"-200,125,200,-125"
CDS_LIB"pure_quanta"
PIN_NAMES_ROTATE"True"
PIN_TEXT_VISIBLE"True"
NEEDS_NO_SIZE"TRUE"
CDS_LOCATION"ME21";
%"TP"
"1","(-1900,-475)","0","pure_quanta","I69";
;
PART_NUMBER"TP12_BOM"
QPN"DFHS56FR016"
MATERIAL"NA"
LOCATION"J90_CON"
CDS_LIB"pure_quanta"
PACK_TYPE"TP_BOM ONLY"
$SEC"1"
CDS_SEC"1";
"TP \B"
$PN"1"
$PIN_NUMBER"?"0;
%"TP"
"1","(-1225,-475)","0","pure_quanta","I70";
;
PART_NUMBER"TP12_BOM"
MATERIAL"NA"
QPN"DEJP0020021"
LOCATION"JP4003_12"
PACK_TYPE"TP_BOM ONLY"
CDS_LIB"pure_quanta"
$SEC"1"
CDS_SEC"1";
"TP \B"
$PN"1"
$PIN_NUMBER"?"0;
%"TP"
"1","(-1225,-775)","0","pure_quanta","I71";
;
PART_NUMBER"TP12_BOM"
MATERIAL"NA"
QPN"DEJP0020021"
LOCATION"JP15_23"
CDS_LIB"pure_quanta"
PACK_TYPE"TP_BOM ONLY"
$SEC"1"
CDS_SEC"1";
"TP \B"
$PN"1"
$PIN_NUMBER"?"0;
%"TP"
"1","(-1225,-1075)","0","pure_quanta","I72";
;
PART_NUMBER"TP12_BOM"
QPN"DEJP0020021"
MATERIAL"NA"
LOCATION"JP16_23"
PACK_TYPE"TP_BOM ONLY"
CDS_LIB"pure_quanta"
$SEC"1"
CDS_SEC"1";
"TP \B"
$PN"1"
$PIN_NUMBER"?"0;
%"ME_DUMMY_SYMBOL"
"1","(3625,4300)","0","pure_quanta","I73";
;
PART_NUMBER"DUMMY46"
MATERIAL"EMPTY"
VALUE"SNLABEL_27X6"
PART_TYPE"MECH"
LOCATION"ME22"
CDS_LIB"pure_quanta"
PIN_NAMES_ROTATE"True"
PIN_TEXT_VISIBLE"True"
NEEDS_NO_SIZE"TRUE"
CDS_LMAN_SYM_OUTLINE"-200,125,200,-125";
%"ME_DUMMY_SYMBOL"
"1","(-2800,1775)","0","pure_quanta","I74";
;
PART_NUMBER"DUMMY47"
MATERIAL"EMPTY"
VALUE"CBS_3X558-8"
PART_TYPE"MECH"
$LOCATION"ME27"
PIN_NAMES_ROTATE"True"
PIN_TEXT_VISIBLE"True"
NEEDS_NO_SIZE"TRUE"
CDS_LMAN_SYM_OUTLINE"-200,125,200,-125"
CDS_LIB"pure_quanta"
CDS_LOCATION"ME27";
%"ME_DUMMY_SYMBOL"
"1","(-225,1800)","0","pure_quanta","I75";
;
PART_NUMBER"DUMMY28_HCLU2002010"
VALUE"EFI BIOS LABEL"
PART_TYPE"MECH"
MATERIAL"EMPTY"
$LOCATION"ME28"
CDS_LIB"pure_quanta"
PIN_NAMES_ROTATE"True"
PIN_TEXT_VISIBLE"True"
NEEDS_NO_SIZE"TRUE"
CDS_LMAN_SYM_OUTLINE"-200,125,200,-125"
CDS_LOCATION"ME28";
%"ME_DUMMY_SYMBOL"
"1","(4250,4275)","0","pure_quanta","I76";
;
PART_NUMBER"DUMMY36"
MATERIAL"EMPTY"
VALUE"SNLABEL_15X5"
PART_TYPE"MECH"
$LOCATION"ME29"
CDS_LMAN_SYM_OUTLINE"-200,125,200,-125"
NEEDS_NO_SIZE"TRUE"
PIN_TEXT_VISIBLE"True"
PIN_NAMES_ROTATE"True"
CDS_LIB"pure_quanta"
CDS_LOCATION"ME29";
%"ME_DUMMY_SYMBOL"
"1","(4225,3275)","0","pure_quanta","I9";
;
PART_NUMBER"DUMMY48"
PART_TYPE"MECH"
MATERIAL"EMPTY"
VALUE"PICKUP_SMDC20"
$LOCATION"ME4"
PIN_NAMES_ROTATE"True"
PIN_TEXT_VISIBLE"True"
NEEDS_NO_SIZE"TRUE"
CDS_LMAN_SYM_OUTLINE"-200,125,200,-125"
CDS_LIB"pure_quanta"
$LOCATION"ME4"
CDS_LOCATION"ME4";
END.
